(kicad_pcb
	(version 20260206)
	(generator "pcbnew")
	(generator_version "10.0")
	(general
		(thickness 1.6)
		(legacy_teardrops no)
	)
	(paper "A4")
	(title_block
		(title "03242023_DA0F0TMBIJ0_F0T_Motherboard_J_brd_V01_OCP.brd")
		(comment 1 "Grand Teton / footprints 2598-2604 of 6105")
	)
	(layers
		(0 "F.Cu" signal "TOP")
		(4 "In1.Cu" signal "GND")
		(6 "In2.Cu" signal "IN1")
		(8 "In3.Cu" signal "GND1")
		(10 "In4.Cu" signal "IN2")
		(12 "In5.Cu" signal "GND2")
		(14 "In6.Cu" signal "IN3")
		(16 "In7.Cu" signal "GND3")
		(18 "In8.Cu" signal "VCC")
		(20 "In9.Cu" signal "VCC1")
		(22 "In10.Cu" signal "GND4")
		(24 "In11.Cu" signal "IN4")
		(26 "In12.Cu" signal "GND5")
		(28 "In13.Cu" signal "IN5")
		(30 "In14.Cu" signal "GND6")
		(32 "In15.Cu" signal "IN6")
		(34 "In16.Cu" signal "GND7")
		(2 "B.Cu" signal "BOTTOM")
		(9 "F.Adhes" user "F.Adhesive")
		(11 "B.Adhes" user "B.Adhesive")
		(13 "F.Paste" user "Package Geometry/Pastemask Top")
		(15 "B.Paste" user "Package Geometry/Pastemask Bottom")
		(5 "F.SilkS" user "Ref Des/Silkscreen Top")
		(7 "B.SilkS" user "Ref Des/Silkscreen Bottom")
		(1 "F.Mask" user "Board Geometry/Soldermask Top")
		(3 "B.Mask" user "Board Geometry/Soldermask Bottom")
		(17 "Dwgs.User" user "User.Drawings")
		(19 "Cmts.User" user "User.Comments")
		(21 "Eco1.User" user "User.Eco1")
		(23 "Eco2.User" user "User.Eco2")
		(25 "Edge.Cuts" user "Board Geometry/Outline")
		(27 "Margin" user)
		(31 "F.CrtYd" user "Package Geometry/Place Bound Top")
		(29 "B.CrtYd" user "Package Geometry/Place Bound Bottom")
		(35 "F.Fab" user "Ref Des/Assembly Top")
		(33 "B.Fab" user "Ref Des/Assembly Bottom")
	)
	(footprint ""
		(layer "F.Cu")
		(at 260.561582 -75.505056)
		(property "Reference" "PR187"
			(at 0 0 0)
			(layer "F.SilkS")
			(hide yes)
			(effects
				(font
					(size 1.27 1.27)
				)
			)
		)
		(property "Value" ""
			(at 0 0 0)
			(layer "F.Fab")
			(effects
				(font
					(size 1.27 1.27)
				)
			)
		)
		(duplicate_pad_numbers_are_jumpers no)
		(fp_line
			(start -0.7874 -0.4064)
			(end 0.7874 -0.4064)
			(stroke
				(width 0.1524)
				(type default)
			)
			(layer "F.SilkS")
		)
		(fp_line
			(start -0.7874 0.4064)
			(end -0.7874 -0.4064)
			(stroke
				(width 0.1524)
				(type default)
			)
			(layer "F.SilkS")
		)
		(fp_line
			(start 0.7874 -0.4064)
			(end 0.7874 0.4064)
			(stroke
				(width 0.1524)
				(type default)
			)
			(layer "F.SilkS")
		)
		(fp_line
			(start 0.7874 0.4064)
			(end -0.7874 0.4064)
			(stroke
				(width 0.1524)
				(type default)
			)
			(layer "F.SilkS")
		)
		(fp_line
			(start -0.67945 -0.305054)
			(end -0.12065 -0.305054)
			(stroke
				(width 0.1)
				(type default)
			)
			(layer "F.Fab")
		)
		(fp_line
			(start -0.67945 0.3048)
			(end -0.67945 -0.305054)
			(stroke
				(width 0.1)
				(type default)
			)
			(layer "F.Fab")
		)
		(fp_line
			(start -0.12065 -0.305054)
			(end -0.12065 -0.2794)
			(stroke
				(width 0.1)
				(type default)
			)
			(layer "F.Fab")
		)
		(fp_line
			(start -0.12065 -0.2794)
			(end 0.12065 -0.2794)
			(stroke
				(width 0.1)
				(type default)
			)
			(layer "F.Fab")
		)
		(fp_line
			(start -0.12065 0.2794)
			(end -0.12065 0.3048)
			(stroke
				(width 0.1)
				(type default)
			)
			(layer "F.Fab")
		)
		(fp_line
			(start -0.12065 0.3048)
			(end -0.67945 0.3048)
			(stroke
				(width 0.1)
				(type default)
			)
			(layer "F.Fab")
		)
		(fp_line
			(start 0.120396 0.2794)
			(end -0.12065 0.2794)
			(stroke
				(width 0.1)
				(type default)
			)
			(layer "F.Fab")
		)
		(fp_line
			(start 0.120396 0.3048)
			(end 0.120396 0.2794)
			(stroke
				(width 0.1)
				(type default)
			)
			(layer "F.Fab")
		)
		(fp_line
			(start 0.12065 -0.3048)
			(end 0.67945 -0.3048)
			(stroke
				(width 0.1)
				(type default)
			)
			(layer "F.Fab")
		)
		(fp_line
			(start 0.12065 -0.2794)
			(end 0.12065 -0.3048)
			(stroke
				(width 0.1)
				(type default)
			)
			(layer "F.Fab")
		)
		(fp_line
			(start 0.67945 -0.3048)
			(end 0.67945 0.3048)
			(stroke
				(width 0.1)
				(type default)
			)
			(layer "F.Fab")
		)
		(fp_line
			(start 0.67945 0.3048)
			(end 0.120396 0.3048)
			(stroke
				(width 0.1)
				(type default)
			)
			(layer "F.Fab")
		)
		(pad "1" smd circle
			(at -0.40005 0)
			(size 0 0)
			(layers "F.Cu" "F.Mask" "F.Paste")
			(net "P1V05_PCH_AUX_FB")
		)
		(pad "2" smd circle
			(at 0.40005 0)
			(size 0 0)
			(layers "F.Cu" "F.Mask" "F.Paste")
			(net "SH_P1V05_PCH_AUX_N")
		)
	)
	(footprint ""
		(layer "F.Cu")
		(at 356.616 -413.095948)
		(property "Reference" "R4563"
			(at 0 0 0)
			(layer "F.SilkS")
			(hide yes)
			(effects
				(font
					(size 1.27 1.27)
				)
			)
		)
		(property "Value" ""
			(at 0 0 0)
			(layer "F.Fab")
			(effects
				(font
					(size 1.27 1.27)
				)
			)
		)
		(duplicate_pad_numbers_are_jumpers no)
		(fp_line
			(start -0.7874 -0.4064)
			(end 0.7874 -0.4064)
			(stroke
				(width 0.1524)
				(type default)
			)
			(layer "F.SilkS")
		)
		(fp_line
			(start -0.7874 0.4064)
			(end -0.7874 -0.4064)
			(stroke
				(width 0.1524)
				(type default)
			)
			(layer "F.SilkS")
		)
		(fp_line
			(start 0.7874 -0.4064)
			(end 0.7874 0.4064)
			(stroke
				(width 0.1524)
				(type default)
			)
			(layer "F.SilkS")
		)
		(fp_line
			(start 0.7874 0.4064)
			(end -0.7874 0.4064)
			(stroke
				(width 0.1524)
				(type default)
			)
			(layer "F.SilkS")
		)
		(fp_line
			(start -0.67945 -0.305054)
			(end -0.12065 -0.305054)
			(stroke
				(width 0.1)
				(type default)
			)
			(layer "F.Fab")
		)
		(fp_line
			(start -0.67945 0.3048)
			(end -0.67945 -0.305054)
			(stroke
				(width 0.1)
				(type default)
			)
			(layer "F.Fab")
		)
		(fp_line
			(start -0.12065 -0.305054)
			(end -0.12065 -0.2794)
			(stroke
				(width 0.1)
				(type default)
			)
			(layer "F.Fab")
		)
		(fp_line
			(start -0.12065 -0.2794)
			(end 0.12065 -0.2794)
			(stroke
				(width 0.1)
				(type default)
			)
			(layer "F.Fab")
		)
		(fp_line
			(start -0.12065 0.2794)
			(end -0.12065 0.3048)
			(stroke
				(width 0.1)
				(type default)
			)
			(layer "F.Fab")
		)
		(fp_line
			(start -0.12065 0.3048)
			(end -0.67945 0.3048)
			(stroke
				(width 0.1)
				(type default)
			)
			(layer "F.Fab")
		)
		(fp_line
			(start 0.120396 0.2794)
			(end -0.12065 0.2794)
			(stroke
				(width 0.1)
				(type default)
			)
			(layer "F.Fab")
		)
		(fp_line
			(start 0.120396 0.3048)
			(end 0.120396 0.2794)
			(stroke
				(width 0.1)
				(type default)
			)
			(layer "F.Fab")
		)
		(fp_line
			(start 0.12065 -0.3048)
			(end 0.67945 -0.3048)
			(stroke
				(width 0.1)
				(type default)
			)
			(layer "F.Fab")
		)
		(fp_line
			(start 0.12065 -0.2794)
			(end 0.12065 -0.3048)
			(stroke
				(width 0.1)
				(type default)
			)
			(layer "F.Fab")
		)
		(fp_line
			(start 0.67945 -0.3048)
			(end 0.67945 0.3048)
			(stroke
				(width 0.1)
				(type default)
			)
			(layer "F.Fab")
		)
		(fp_line
			(start 0.67945 0.3048)
			(end 0.120396 0.3048)
			(stroke
				(width 0.1)
				(type default)
			)
			(layer "F.Fab")
		)
		(pad "1" smd circle
			(at -0.40005 0)
			(size 0 0)
			(layers "F.Cu" "F.Mask" "F.Paste")
			(net "SWB_HSC_PWRGD_ISO_R")
		)
		(pad "2" smd circle
			(at 0.40005 0)
			(size 0 0)
			(layers "F.Cu" "F.Mask" "F.Paste")
			(net "SWB_HSC_PWRGD_ISO")
		)
	)
	(footprint ""
		(layer "F.Cu")
		(at 306.83454 -430.6697 -90)
		(property "Reference" "C2269"
			(at 0 0 270)
			(layer "F.SilkS")
			(hide yes)
			(effects
				(font
					(size 1.27 1.27)
				)
			)
		)
		(property "Value" ""
			(at 0 0 270)
			(layer "F.Fab")
			(effects
				(font
					(size 1.27 1.27)
				)
			)
		)
		(duplicate_pad_numbers_are_jumpers no)
		(fp_line
			(start -0.7874 0.4064)
			(end -0.7874 -0.4064)
			(stroke
				(width 0.1524)
				(type default)
			)
			(layer "F.SilkS")
		)
		(fp_line
			(start 0.7874 0.4064)
			(end -0.7874 0.4064)
			(stroke
				(width 0.1524)
				(type default)
			)
			(layer "F.SilkS")
		)
		(fp_line
			(start -0.7874 -0.4064)
			(end 0.7874 -0.4064)
			(stroke
				(width 0.1524)
				(type default)
			)
			(layer "F.SilkS")
		)
		(fp_line
			(start 0.7874 -0.4064)
			(end 0.7874 0.4064)
			(stroke
				(width 0.1524)
				(type default)
			)
			(layer "F.SilkS")
		)
		(fp_line
			(start -0.67945 0.3048)
			(end -0.67945 -0.305054)
			(stroke
				(width 0.1)
				(type default)
			)
			(layer "F.Fab")
		)
		(fp_line
			(start -0.12065 0.3048)
			(end -0.67945 0.3048)
			(stroke
				(width 0.1)
				(type default)
			)
			(layer "F.Fab")
		)
		(fp_line
			(start 0.120396 0.3048)
			(end 0.120396 0.2794)
			(stroke
				(width 0.1)
				(type default)
			)
			(layer "F.Fab")
		)
		(fp_line
			(start 0.67945 0.3048)
			(end 0.120396 0.3048)
			(stroke
				(width 0.1)
				(type default)
			)
			(layer "F.Fab")
		)
		(fp_line
			(start -0.12065 0.2794)
			(end -0.12065 0.3048)
			(stroke
				(width 0.1)
				(type default)
			)
			(layer "F.Fab")
		)
		(fp_line
			(start 0.120396 0.2794)
			(end -0.12065 0.2794)
			(stroke
				(width 0.1)
				(type default)
			)
			(layer "F.Fab")
		)
		(fp_line
			(start -0.12065 -0.2794)
			(end 0.12065 -0.2794)
			(stroke
				(width 0.1)
				(type default)
			)
			(layer "F.Fab")
		)
		(fp_line
			(start 0.12065 -0.2794)
			(end 0.12065 -0.3048)
			(stroke
				(width 0.1)
				(type default)
			)
			(layer "F.Fab")
		)
		(fp_line
			(start 0.12065 -0.3048)
			(end 0.67945 -0.3048)
			(stroke
				(width 0.1)
				(type default)
			)
			(layer "F.Fab")
		)
		(fp_line
			(start 0.67945 -0.3048)
			(end 0.67945 0.3048)
			(stroke
				(width 0.1)
				(type default)
			)
			(layer "F.Fab")
		)
		(fp_line
			(start -0.67945 -0.305054)
			(end -0.12065 -0.305054)
			(stroke
				(width 0.1)
				(type default)
			)
			(layer "F.Fab")
		)
		(fp_line
			(start -0.12065 -0.305054)
			(end -0.12065 -0.2794)
			(stroke
				(width 0.1)
				(type default)
			)
			(layer "F.Fab")
		)
		(pad "1" smd circle
			(at -0.40005 0 270)
			(size 0 0)
			(layers "F.Cu" "F.Mask" "F.Paste")
			(net "PRSNT_CABLE_GPU_A2_ISO_N")
		)
		(pad "2" smd circle
			(at 0.40005 0 270)
			(size 0 0)
			(layers "F.Cu" "F.Mask" "F.Paste")
			(net "GND")
		)
	)
	(footprint ""
		(layer "F.Cu")
		(at 139.423394 -402.371052 -90)
		(property "Reference" "C754"
			(at 0 0 270)
			(layer "F.SilkS")
			(hide yes)
			(effects
				(font
					(size 1.27 1.27)
				)
			)
		)
		(property "Value" ""
			(at 0 0 270)
			(layer "F.Fab")
			(effects
				(font
					(size 1.27 1.27)
				)
			)
		)
		(duplicate_pad_numbers_are_jumpers no)
		(fp_line
			(start -0.299974 0.150114)
			(end -0.299974 -0.150114)
			(stroke
				(width 0.1)
				(type default)
			)
			(layer "F.Fab")
		)
		(fp_line
			(start 0.299974 0.150114)
			(end -0.299974 0.150114)
			(stroke
				(width 0.1)
				(type default)
			)
			(layer "F.Fab")
		)
		(fp_line
			(start -0.299974 -0.150114)
			(end 0.299974 -0.150114)
			(stroke
				(width 0.1)
				(type default)
			)
			(layer "F.Fab")
		)
		(fp_line
			(start 0.299974 -0.150114)
			(end 0.299974 0.150114)
			(stroke
				(width 0.1)
				(type default)
			)
			(layer "F.Fab")
		)
		(pad "1" smd rect
			(at -0.2667 0 270)
			(size 0.3048 0.381)
			(layers "F.Cu" "F.Mask" "F.Paste")
			(net "P5E_CPU1_PE2_TX_C_DN<9>")
		)
		(pad "2" smd rect
			(at 0.2667 0 270)
			(size 0.3048 0.381)
			(layers "F.Cu" "F.Mask" "F.Paste")
			(net "P5E_CPU1_PE2_TX_DN<9>")
		)
	)
	(footprint ""
		(layer "F.Cu")
		(at 61.980572 -178.662838 180)
		(property "Reference" "PC434"
			(at 0 0 180)
			(layer "F.SilkS")
			(hide yes)
			(effects
				(font
					(size 1.27 1.27)
				)
			)
		)
		(property "Value" ""
			(at 0 0 180)
			(layer "F.Fab")
			(effects
				(font
					(size 1.27 1.27)
				)
			)
		)
		(duplicate_pad_numbers_are_jumpers no)
		(fp_line
			(start 0.7874 0.4064)
			(end -0.7874 0.4064)
			(stroke
				(width 0.1524)
				(type default)
			)
			(layer "F.SilkS")
		)
		(fp_line
			(start 0.7874 -0.4064)
			(end 0.7874 0.4064)
			(stroke
				(width 0.1524)
				(type default)
			)
			(layer "F.SilkS")
		)
		(fp_line
			(start -0.7874 0.4064)
			(end -0.7874 -0.4064)
			(stroke
				(width 0.1524)
				(type default)
			)
			(layer "F.SilkS")
		)
		(fp_line
			(start -0.7874 -0.4064)
			(end 0.7874 -0.4064)
			(stroke
				(width 0.1524)
				(type default)
			)
			(layer "F.SilkS")
		)
		(fp_line
			(start 0.67945 0.3048)
			(end 0.120396 0.3048)
			(stroke
				(width 0.1)
				(type default)
			)
			(layer "F.Fab")
		)
		(fp_line
			(start 0.67945 -0.3048)
			(end 0.67945 0.3048)
			(stroke
				(width 0.1)
				(type default)
			)
			(layer "F.Fab")
		)
		(fp_line
			(start 0.12065 -0.2794)
			(end 0.12065 -0.3048)
			(stroke
				(width 0.1)
				(type default)
			)
			(layer "F.Fab")
		)
		(fp_line
			(start 0.12065 -0.3048)
			(end 0.67945 -0.3048)
			(stroke
				(width 0.1)
				(type default)
			)
			(layer "F.Fab")
		)
		(fp_line
			(start 0.120396 0.3048)
			(end 0.120396 0.2794)
			(stroke
				(width 0.1)
				(type default)
			)
			(layer "F.Fab")
		)
		(fp_line
			(start 0.120396 0.2794)
			(end -0.12065 0.2794)
			(stroke
				(width 0.1)
				(type default)
			)
			(layer "F.Fab")
		)
		(fp_line
			(start -0.12065 0.3048)
			(end -0.67945 0.3048)
			(stroke
				(width 0.1)
				(type default)
			)
			(layer "F.Fab")
		)
		(fp_line
			(start -0.12065 0.2794)
			(end -0.12065 0.3048)
			(stroke
				(width 0.1)
				(type default)
			)
			(layer "F.Fab")
		)
		(fp_line
			(start -0.12065 -0.2794)
			(end 0.12065 -0.2794)
			(stroke
				(width 0.1)
				(type default)
			)
			(layer "F.Fab")
		)
		(fp_line
			(start -0.12065 -0.305054)
			(end -0.12065 -0.2794)
			(stroke
				(width 0.1)
				(type default)
			)
			(layer "F.Fab")
		)
		(fp_line
			(start -0.67945 0.3048)
			(end -0.67945 -0.305054)
			(stroke
				(width 0.1)
				(type default)
			)
			(layer "F.Fab")
		)
		(fp_line
			(start -0.67945 -0.305054)
			(end -0.12065 -0.305054)
			(stroke
				(width 0.1)
				(type default)
			)
			(layer "F.Fab")
		)
		(pad "1" smd circle
			(at -0.40005 0 180)
			(size 0 0)
			(layers "F.Cu" "F.Mask" "F.Paste")
			(net "PVCCFA_EHV_CPU1")
		)
		(pad "2" smd circle
			(at 0.40005 0 180)
			(size 0 0)
			(layers "F.Cu" "F.Mask" "F.Paste")
			(net "GND")
		)
	)
	(footprint ""
		(layer "F.Cu")
		(at 211.99221 -26.868374 -90)
		(property "Reference" "C1274"
			(at 0 0 270)
			(layer "F.SilkS")
			(hide yes)
			(effects
				(font
					(size 1.27 1.27)
				)
			)
		)
		(property "Value" ""
			(at 0 0 270)
			(layer "F.Fab")
			(effects
				(font
					(size 1.27 1.27)
				)
			)
		)
		(duplicate_pad_numbers_are_jumpers no)
		(fp_line
			(start -0.7874 0.4064)
			(end -0.7874 -0.4064)
			(stroke
				(width 0.1524)
				(type default)
			)
			(layer "F.SilkS")
		)
		(fp_line
			(start 0.7874 0.4064)
			(end -0.7874 0.4064)
			(stroke
				(width 0.1524)
				(type default)
			)
			(layer "F.SilkS")
		)
		(fp_line
			(start -0.7874 -0.4064)
			(end 0.7874 -0.4064)
			(stroke
				(width 0.1524)
				(type default)
			)
			(layer "F.SilkS")
		)
		(fp_line
			(start 0.7874 -0.4064)
			(end 0.7874 0.4064)
			(stroke
				(width 0.1524)
				(type default)
			)
			(layer "F.SilkS")
		)
		(fp_line
			(start -0.67945 0.3048)
			(end -0.67945 -0.305054)
			(stroke
				(width 0.1)
				(type default)
			)
			(layer "F.Fab")
		)
		(fp_line
			(start -0.12065 0.3048)
			(end -0.67945 0.3048)
			(stroke
				(width 0.1)
				(type default)
			)
			(layer "F.Fab")
		)
		(fp_line
			(start 0.120396 0.3048)
			(end 0.120396 0.2794)
			(stroke
				(width 0.1)
				(type default)
			)
			(layer "F.Fab")
		)
		(fp_line
			(start 0.67945 0.3048)
			(end 0.120396 0.3048)
			(stroke
				(width 0.1)
				(type default)
			)
			(layer "F.Fab")
		)
		(fp_line
			(start -0.12065 0.2794)
			(end -0.12065 0.3048)
			(stroke
				(width 0.1)
				(type default)
			)
			(layer "F.Fab")
		)
		(fp_line
			(start 0.120396 0.2794)
			(end -0.12065 0.2794)
			(stroke
				(width 0.1)
				(type default)
			)
			(layer "F.Fab")
		)
		(fp_line
			(start -0.12065 -0.2794)
			(end 0.12065 -0.2794)
			(stroke
				(width 0.1)
				(type default)
			)
			(layer "F.Fab")
		)
		(fp_line
			(start 0.12065 -0.2794)
			(end 0.12065 -0.3048)
			(stroke
				(width 0.1)
				(type default)
			)
			(layer "F.Fab")
		)
		(fp_line
			(start 0.12065 -0.3048)
			(end 0.67945 -0.3048)
			(stroke
				(width 0.1)
				(type default)
			)
			(layer "F.Fab")
		)
		(fp_line
			(start 0.67945 -0.3048)
			(end 0.67945 0.3048)
			(stroke
				(width 0.1)
				(type default)
			)
			(layer "F.Fab")
		)
		(fp_line
			(start -0.67945 -0.305054)
			(end -0.12065 -0.305054)
			(stroke
				(width 0.1)
				(type default)
			)
			(layer "F.Fab")
		)
		(fp_line
			(start -0.12065 -0.305054)
			(end -0.12065 -0.2794)
			(stroke
				(width 0.1)
				(type default)
			)
			(layer "F.Fab")
		)
		(pad "1" smd circle
			(at -0.40005 0 270)
			(size 0 0)
			(layers "F.Cu" "F.Mask" "F.Paste")
			(net "P3V3_AUX")
		)
		(pad "2" smd circle
			(at 0.40005 0 270)
			(size 0 0)
			(layers "F.Cu" "F.Mask" "F.Paste")
			(net "GND")
		)
	)
	(footprint ""
		(layer "F.Cu")
		(at 24.046942 -416.143948 180)
		(property "Reference" "R3513"
			(at 0 0 180)
			(layer "F.SilkS")
			(hide yes)
			(effects
				(font
					(size 1.27 1.27)
				)
			)
		)
		(property "Value" ""
			(at 0 0 180)
			(layer "F.Fab")
			(effects
				(font
					(size 1.27 1.27)
				)
			)
		)
		(duplicate_pad_numbers_are_jumpers no)
		(fp_line
			(start 0.7874 0.4064)
			(end -0.7874 0.4064)
			(stroke
				(width 0.1524)
				(type default)
			)
			(layer "F.SilkS")
		)
		(fp_line
			(start 0.7874 -0.4064)
			(end 0.7874 0.4064)
			(stroke
				(width 0.1524)
				(type default)
			)
			(layer "F.SilkS")
		)
		(fp_line
			(start -0.7874 0.4064)
			(end -0.7874 -0.4064)
			(stroke
				(width 0.1524)
				(type default)
			)
			(layer "F.SilkS")
		)
		(fp_line
			(start -0.7874 -0.4064)
			(end 0.7874 -0.4064)
			(stroke
				(width 0.1524)
				(type default)
			)
			(layer "F.SilkS")
		)
		(fp_line
			(start 0.67945 0.3048)
			(end 0.120396 0.3048)
			(stroke
				(width 0.1)
				(type default)
			)
			(layer "F.Fab")
		)
		(fp_line
			(start 0.67945 -0.3048)
			(end 0.67945 0.3048)
			(stroke
				(width 0.1)
				(type default)
			)
			(layer "F.Fab")
		)
		(fp_line
			(start 0.12065 -0.2794)
			(end 0.12065 -0.3048)
			(stroke
				(width 0.1)
				(type default)
			)
			(layer "F.Fab")
		)
		(fp_line
			(start 0.12065 -0.3048)
			(end 0.67945 -0.3048)
			(stroke
				(width 0.1)
				(type default)
			)
			(layer "F.Fab")
		)
		(fp_line
			(start 0.120396 0.3048)
			(end 0.120396 0.2794)
			(stroke
				(width 0.1)
				(type default)
			)
			(layer "F.Fab")
		)
		(fp_line
			(start 0.120396 0.2794)
			(end -0.12065 0.2794)
			(stroke
				(width 0.1)
				(type default)
			)
			(layer "F.Fab")
		)
		(fp_line
			(start -0.12065 0.3048)
			(end -0.67945 0.3048)
			(stroke
				(width 0.1)
				(type default)
			)
			(layer "F.Fab")
		)
		(fp_line
			(start -0.12065 0.2794)
			(end -0.12065 0.3048)
			(stroke
				(width 0.1)
				(type default)
			)
			(layer "F.Fab")
		)
		(fp_line
			(start -0.12065 -0.2794)
			(end 0.12065 -0.2794)
			(stroke
				(width 0.1)
				(type default)
			)
			(layer "F.Fab")
		)
		(fp_line
			(start -0.12065 -0.305054)
			(end -0.12065 -0.2794)
			(stroke
				(width 0.1)
				(type default)
			)
			(layer "F.Fab")
		)
		(fp_line
			(start -0.67945 0.3048)
			(end -0.67945 -0.305054)
			(stroke
				(width 0.1)
				(type default)
			)
			(layer "F.Fab")
		)
		(fp_line
			(start -0.67945 -0.305054)
			(end -0.12065 -0.305054)
			(stroke
				(width 0.1)
				(type default)
			)
			(layer "F.Fab")
		)
		(pad "1" smd circle
			(at -0.40005 0 180)
			(size 0 0)
			(layers "F.Cu" "F.Mask" "F.Paste")
			(net "FM_GPU_PWRGD")
		)
		(pad "2" smd circle
			(at 0.40005 0 180)
			(size 0 0)
			(layers "F.Cu" "F.Mask" "F.Paste")
			(net "GND")
		)
	)
)
